# T6G (Grand Teton) — schematic netlist excerpt (pin names and nets, part order shuffled) for the footprints in the layout excerpt that follows; sources: Cadence DE-HDL packaged netlist, KiCad conversion of 04192023_DAF0TMB3IC0_F0TG_MB_C_brd_V02_OCP.brd

PR283  Q_RES  0 5% CHIP  pkg 0402LF  page 193 : A = SVID_PVDDCR_CPU0_P0_SVTI ; B = GND
R1386  Q_RES  2K 1% EMPTY  pkg 0402LF  page 151 : A = SMB_PMBUS_3V3AUX_SCL ; B = P3V3_AUX

(kicad_pcb
	(version 20260206)
	(generator "pcbnew")
	(generator_version "10.0")
	(general
		(thickness 1.6)
		(legacy_teardrops no)
	)
	(paper "A4")
	(title_block
		(title "04192023_DAF0TMB3IC0_F0TG_MB_C_brd_V02_OCP.brd")
		(comment 1 "Grand Teton / footprints 5989-5990 of 8354")
	)
	(layers
		(0 "F.Cu" signal "TOP")
		(4 "In1.Cu" signal "GND")
		(6 "In2.Cu" signal "IN1")
		(8 "In3.Cu" signal "GND1")
		(10 "In4.Cu" signal "IN2")
		(12 "In5.Cu" signal "GND2")
		(14 "In6.Cu" signal "IN3")
		(16 "In7.Cu" signal "GND3")
		(18 "In8.Cu" signal "VCC")
		(20 "In9.Cu" signal "VCC1")
		(22 "In10.Cu" signal "GND4")
		(24 "In11.Cu" signal "IN4")
		(26 "In12.Cu" signal "GND5")
		(28 "In13.Cu" signal "IN5")
		(30 "In14.Cu" signal "GND6")
		(32 "In15.Cu" signal "IN6")
		(34 "In16.Cu" signal "GND7")
		(2 "B.Cu" signal "BOTTOM")
		(9 "F.Adhes" user "F.Adhesive")
		(11 "B.Adhes" user "B.Adhesive")
		(13 "F.Paste" user "Package Geometry/Pastemask Top")
		(15 "B.Paste" user "Package Geometry/Pastemask Bottom")
		(5 "F.SilkS" user "Ref Des/Silkscreen Top")
		(7 "B.SilkS" user "Ref Des/Silkscreen Bottom")
		(1 "F.Mask" user "Board Geometry/Soldermask Top")
		(3 "B.Mask" user "Board Geometry/Soldermask Bottom")
		(17 "Dwgs.User" user "User.Drawings")
		(19 "Cmts.User" user "User.Comments")
		(21 "Eco1.User" user "User.Eco1")
		(23 "Eco2.User" user "User.Eco2")
		(25 "Edge.Cuts" user "Board Geometry/Outline")
		(27 "Margin" user)
		(31 "F.CrtYd" user "Package Geometry/Place Bound Top")
		(29 "B.CrtYd" user "Package Geometry/Place Bound Bottom")
		(35 "F.Fab" user "Ref Des/Assembly Top")
		(33 "B.Fab" user "Ref Des/Assembly Bottom")
	)
	(footprint ""
		(layer "B.Cu")
		(at 168.367202 -14.4653 -90)
		(property "Reference" "R1386"
			(at 0 0 90)
			(layer "B.SilkS")
			(hide yes)
			(effects
				(font
					(size 1.27 1.27)
				)
				(justify mirror)
			)
		)
		(property "Value" ""
			(at 0 0 90)
			(layer "B.Fab")
			(effects
				(font
					(size 1.27 1.27)
				)
				(justify mirror)
			)
		)
		(duplicate_pad_numbers_are_jumpers no)
		(fp_line
			(start -0.7874 0.4064)
			(end 0.7874 0.4064)
			(stroke
				(width 0.1524)
				(type default)
			)
			(layer "B.SilkS")
		)
		(fp_line
			(start 0.7874 0.4064)
			(end 0.7874 -0.4064)
			(stroke
				(width 0.1524)
				(type default)
			)
			(layer "B.SilkS")
		)
		(fp_line
			(start -0.7874 -0.4064)
			(end -0.7874 0.4064)
			(stroke
				(width 0.1524)
				(type default)
			)
			(layer "B.SilkS")
		)
		(fp_line
			(start 0.7874 -0.4064)
			(end -0.7874 -0.4064)
			(stroke
				(width 0.1524)
				(type default)
			)
			(layer "B.SilkS")
		)
		(fp_line
			(start -0.67945 0.3048)
			(end -0.120396 0.3048)
			(stroke
				(width 0.1)
				(type default)
			)
			(layer "B.Fab")
		)
		(fp_line
			(start -0.120396 0.3048)
			(end -0.120396 0.2794)
			(stroke
				(width 0.1)
				(type default)
			)
			(layer "B.Fab")
		)
		(fp_line
			(start 0.12065 0.3048)
			(end 0.67945 0.3048)
			(stroke
				(width 0.1)
				(type default)
			)
			(layer "B.Fab")
		)
		(fp_line
			(start 0.67945 0.3048)
			(end 0.67945 -0.305054)
			(stroke
				(width 0.1)
				(type default)
			)
			(layer "B.Fab")
		)
		(fp_line
			(start -0.120396 0.2794)
			(end 0.12065 0.2794)
			(stroke
				(width 0.1)
				(type default)
			)
			(layer "B.Fab")
		)
		(fp_line
			(start 0.12065 0.2794)
			(end 0.12065 0.3048)
			(stroke
				(width 0.1)
				(type default)
			)
			(layer "B.Fab")
		)
		(fp_line
			(start -0.12065 -0.2794)
			(end -0.12065 -0.3048)
			(stroke
				(width 0.1)
				(type default)
			)
			(layer "B.Fab")
		)
		(fp_line
			(start 0.12065 -0.2794)
			(end -0.12065 -0.2794)
			(stroke
				(width 0.1)
				(type default)
			)
			(layer "B.Fab")
		)
		(fp_line
			(start -0.67945 -0.3048)
			(end -0.67945 0.3048)
			(stroke
				(width 0.1)
				(type default)
			)
			(layer "B.Fab")
		)
		(fp_line
			(start -0.12065 -0.3048)
			(end -0.67945 -0.3048)
			(stroke
				(width 0.1)
				(type default)
			)
			(layer "B.Fab")
		)
		(fp_line
			(start 0.12065 -0.305054)
			(end 0.12065 -0.2794)
			(stroke
				(width 0.1)
				(type default)
			)
			(layer "B.Fab")
		)
		(fp_line
			(start 0.67945 -0.305054)
			(end 0.12065 -0.305054)
			(stroke
				(width 0.1)
				(type default)
			)
			(layer "B.Fab")
		)
		(pad "1" smd circle
			(at 0.40005 0 90)
			(size 0 0)
			(layers "B.Cu" "B.Mask" "B.Paste")
			(net "SMB_PMBUS_3V3AUX_SCL")
		)
		(pad "2" smd circle
			(at -0.40005 0 90)
			(size 0 0)
			(layers "B.Cu" "B.Mask" "B.Paste")
			(net "P3V3_AUX")
		)
	)
	(footprint ""
		(layer "B.Cu")
		(at 370.905278 -147.568158)
		(property "Reference" "PR283"
			(at 0 0 0)
			(layer "B.SilkS")
			(hide yes)
			(effects
				(font
					(size 1.27 1.27)
				)
				(justify mirror)
			)
		)
		(property "Value" ""
			(at 0 0 0)
			(layer "B.Fab")
			(effects
				(font
					(size 1.27 1.27)
				)
				(justify mirror)
			)
		)
		(duplicate_pad_numbers_are_jumpers no)
		(fp_line
			(start -0.7874 -0.4064)
			(end -0.7874 0.4064)
			(stroke
				(width 0.1524)
				(type default)
			)
			(layer "B.SilkS")
		)
		(fp_line
			(start -0.7874 0.4064)
			(end 0.7874 0.4064)
			(stroke
				(width 0.1524)
				(type default)
			)
			(layer "B.SilkS")
		)
		(fp_line
			(start 0.7874 -0.4064)
			(end -0.7874 -0.4064)
			(stroke
				(width 0.1524)
				(type default)
			)
			(layer "B.SilkS")
		)
		(fp_line
			(start 0.7874 0.4064)
			(end 0.7874 -0.4064)
			(stroke
				(width 0.1524)
				(type default)
			)
			(layer "B.SilkS")
		)
		(fp_line
			(start -0.67945 -0.3048)
			(end -0.67945 0.3048)
			(stroke
				(width 0.1)
				(type default)
			)
			(layer "B.Fab")
		)
		(fp_line
			(start -0.67945 0.3048)
			(end -0.120396 0.3048)
			(stroke
				(width 0.1)
				(type default)
			)
			(layer "B.Fab")
		)
		(fp_line
			(start -0.12065 -0.3048)
			(end -0.67945 -0.3048)
			(stroke
				(width 0.1)
				(type default)
			)
			(layer "B.Fab")
		)
		(fp_line
			(start -0.12065 -0.2794)
			(end -0.12065 -0.3048)
			(stroke
				(width 0.1)
				(type default)
			)
			(layer "B.Fab")
		)
		(fp_line
			(start -0.120396 0.2794)
			(end 0.12065 0.2794)
			(stroke
				(width 0.1)
				(type default)
			)
			(layer "B.Fab")
		)
		(fp_line
			(start -0.120396 0.3048)
			(end -0.120396 0.2794)
			(stroke
				(width 0.1)
				(type default)
			)
			(layer "B.Fab")
		)
		(fp_line
			(start 0.12065 -0.305054)
			(end 0.12065 -0.2794)
			(stroke
				(width 0.1)
				(type default)
			)
			(layer "B.Fab")
		)
		(fp_line
			(start 0.12065 -0.2794)
			(end -0.12065 -0.2794)
			(stroke
				(width 0.1)
				(type default)
			)
			(layer "B.Fab")
		)
		(fp_line
			(start 0.12065 0.2794)
			(end 0.12065 0.3048)
			(stroke
				(width 0.1)
				(type default)
			)
			(layer "B.Fab")
		)
		(fp_line
			(start 0.12065 0.3048)
			(end 0.67945 0.3048)
			(stroke
				(width 0.1)
				(type default)
			)
			(layer "B.Fab")
		)
		(fp_line
			(start 0.67945 -0.305054)
			(end 0.12065 -0.305054)
			(stroke
				(width 0.1)
				(type default)
			)
			(layer "B.Fab")
		)
		(fp_line
			(start 0.67945 0.3048)
			(end 0.67945 -0.305054)
			(stroke
				(width 0.1)
				(type default)
			)
			(layer "B.Fab")
		)
		(pad "1" smd circle
			(at 0.40005 0 180)
			(size 0 0)
			(layers "B.Cu" "B.Mask" "B.Paste")
			(net "SVID_PVDDCR_CPU0_P0_SVTI")
		)
		(pad "2" smd circle
			(at -0.40005 0 180)
			(size 0 0)
			(layers "B.Cu" "B.Mask" "B.Paste")
			(net "GND")
		)
	)
)
